# T6G (Grand Teton) — schematic netlist excerpt (pin names and nets, part order shuffled) for the footprints in the layout excerpt that follows; sources: Cadence DE-HDL packaged netlist, KiCad conversion of 04192023_DAF0TMB3IC0_F0TG_MB_C_brd_V02_OCP.brd

C2132  Q_CAP  22UF 4V 20% X6S  pkg C0402  page 68 : A = PVDD11_S3_P0 ; B = GND
PC2281  Q_CAP  0.047UF 25V 10% X7R  pkg C0402  page 147 : A = P12V_E1S_SS_0 ; B = GND

(kicad_pcb
	(version 20260206)
	(generator "pcbnew")
	(generator_version "10.0")
	(general
		(thickness 1.6)
		(legacy_teardrops no)
	)
	(paper "A4")
	(title_block
		(title "04192023_DAF0TMB3IC0_F0TG_MB_C_brd_V02_OCP.brd")
		(comment 1 "Grand Teton / footprints 4115-4116 of 8354")
	)
	(layers
		(0 "F.Cu" signal "TOP")
		(4 "In1.Cu" signal "GND")
		(6 "In2.Cu" signal "IN1")
		(8 "In3.Cu" signal "GND1")
		(10 "In4.Cu" signal "IN2")
		(12 "In5.Cu" signal "GND2")
		(14 "In6.Cu" signal "IN3")
		(16 "In7.Cu" signal "GND3")
		(18 "In8.Cu" signal "VCC")
		(20 "In9.Cu" signal "VCC1")
		(22 "In10.Cu" signal "GND4")
		(24 "In11.Cu" signal "IN4")
		(26 "In12.Cu" signal "GND5")
		(28 "In13.Cu" signal "IN5")
		(30 "In14.Cu" signal "GND6")
		(32 "In15.Cu" signal "IN6")
		(34 "In16.Cu" signal "GND7")
		(2 "B.Cu" signal "BOTTOM")
		(9 "F.Adhes" user "F.Adhesive")
		(11 "B.Adhes" user "B.Adhesive")
		(13 "F.Paste" user "Package Geometry/Pastemask Top")
		(15 "B.Paste" user "Package Geometry/Pastemask Bottom")
		(5 "F.SilkS" user "Ref Des/Silkscreen Top")
		(7 "B.SilkS" user "Ref Des/Silkscreen Bottom")
		(1 "F.Mask" user "Board Geometry/Soldermask Top")
		(3 "B.Mask" user "Board Geometry/Soldermask Bottom")
		(17 "Dwgs.User" user "User.Drawings")
		(19 "Cmts.User" user "User.Comments")
		(21 "Eco1.User" user "User.Eco1")
		(23 "Eco2.User" user "User.Eco2")
		(25 "Edge.Cuts" user "Board Geometry/Outline")
		(27 "Margin" user)
		(31 "F.CrtYd" user "Package Geometry/Place Bound Top")
		(29 "B.CrtYd" user "Package Geometry/Place Bound Bottom")
		(35 "F.Fab" user "Ref Des/Assembly Top")
		(33 "B.Fab" user "Ref Des/Assembly Bottom")
	)
	(footprint ""
		(layer "F.Cu")
		(at 358.796082 -259.845048)
		(property "Reference" "C2132"
			(at 0 0 0)
			(layer "F.SilkS")
			(hide yes)
			(effects
				(font
					(size 1.27 1.27)
				)
			)
		)
		(property "Value" ""
			(at 0 0 0)
			(layer "F.Fab")
			(effects
				(font
					(size 1.27 1.27)
				)
			)
		)
		(duplicate_pad_numbers_are_jumpers no)
		(fp_line
			(start -0.7874 -0.4064)
			(end 0.7874 -0.4064)
			(stroke
				(width 0.1524)
				(type default)
			)
			(layer "F.SilkS")
		)
		(fp_line
			(start -0.7874 0.4064)
			(end -0.7874 -0.4064)
			(stroke
				(width 0.1524)
				(type default)
			)
			(layer "F.SilkS")
		)
		(fp_line
			(start 0.7874 -0.4064)
			(end 0.7874 0.4064)
			(stroke
				(width 0.1524)
				(type default)
			)
			(layer "F.SilkS")
		)
		(fp_line
			(start 0.7874 0.4064)
			(end -0.7874 0.4064)
			(stroke
				(width 0.1524)
				(type default)
			)
			(layer "F.SilkS")
		)
		(fp_line
			(start -0.67945 -0.305054)
			(end -0.12065 -0.305054)
			(stroke
				(width 0.1)
				(type default)
			)
			(layer "F.Fab")
		)
		(fp_line
			(start -0.67945 0.3048)
			(end -0.67945 -0.305054)
			(stroke
				(width 0.1)
				(type default)
			)
			(layer "F.Fab")
		)
		(fp_line
			(start -0.12065 -0.305054)
			(end -0.12065 -0.2794)
			(stroke
				(width 0.1)
				(type default)
			)
			(layer "F.Fab")
		)
		(fp_line
			(start -0.12065 -0.2794)
			(end 0.12065 -0.2794)
			(stroke
				(width 0.1)
				(type default)
			)
			(layer "F.Fab")
		)
		(fp_line
			(start -0.12065 0.2794)
			(end -0.12065 0.3048)
			(stroke
				(width 0.1)
				(type default)
			)
			(layer "F.Fab")
		)
		(fp_line
			(start -0.12065 0.3048)
			(end -0.67945 0.3048)
			(stroke
				(width 0.1)
				(type default)
			)
			(layer "F.Fab")
		)
		(fp_line
			(start 0.120396 0.2794)
			(end -0.12065 0.2794)
			(stroke
				(width 0.1)
				(type default)
			)
			(layer "F.Fab")
		)
		(fp_line
			(start 0.120396 0.3048)
			(end 0.120396 0.2794)
			(stroke
				(width 0.1)
				(type default)
			)
			(layer "F.Fab")
		)
		(fp_line
			(start 0.12065 -0.3048)
			(end 0.67945 -0.3048)
			(stroke
				(width 0.1)
				(type default)
			)
			(layer "F.Fab")
		)
		(fp_line
			(start 0.12065 -0.2794)
			(end 0.12065 -0.3048)
			(stroke
				(width 0.1)
				(type default)
			)
			(layer "F.Fab")
		)
		(fp_line
			(start 0.67945 -0.3048)
			(end 0.67945 0.3048)
			(stroke
				(width 0.1)
				(type default)
			)
			(layer "F.Fab")
		)
		(fp_line
			(start 0.67945 0.3048)
			(end 0.120396 0.3048)
			(stroke
				(width 0.1)
				(type default)
			)
			(layer "F.Fab")
		)
		(pad "1" smd circle
			(at -0.40005 0)
			(size 0 0)
			(layers "F.Cu" "F.Mask" "F.Paste")
			(net "PVDD11_S3_P0")
		)
		(pad "2" smd circle
			(at 0.40005 0)
			(size 0 0)
			(layers "F.Cu" "F.Mask" "F.Paste")
			(net "GND")
		)
	)
	(footprint ""
		(layer "F.Cu")
		(at 257.85953 -52.685442)
		(property "Reference" "PC2281"
			(at 0 0 0)
			(layer "F.SilkS")
			(hide yes)
			(effects
				(font
					(size 1.27 1.27)
				)
			)
		)
		(property "Value" ""
			(at 0 0 0)
			(layer "F.Fab")
			(effects
				(font
					(size 1.27 1.27)
				)
			)
		)
		(duplicate_pad_numbers_are_jumpers no)
		(fp_line
			(start -0.7874 -0.4064)
			(end 0.7874 -0.4064)
			(stroke
				(width 0.1524)
				(type default)
			)
			(layer "F.SilkS")
		)
		(fp_line
			(start -0.7874 0.4064)
			(end -0.7874 -0.4064)
			(stroke
				(width 0.1524)
				(type default)
			)
			(layer "F.SilkS")
		)
		(fp_line
			(start 0.7874 -0.4064)
			(end 0.7874 0.4064)
			(stroke
				(width 0.1524)
				(type default)
			)
			(layer "F.SilkS")
		)
		(fp_line
			(start 0.7874 0.4064)
			(end -0.7874 0.4064)
			(stroke
				(width 0.1524)
				(type default)
			)
			(layer "F.SilkS")
		)
		(fp_line
			(start -0.67945 -0.305054)
			(end -0.12065 -0.305054)
			(stroke
				(width 0.1)
				(type default)
			)
			(layer "F.Fab")
		)
		(fp_line
			(start -0.67945 0.3048)
			(end -0.67945 -0.305054)
			(stroke
				(width 0.1)
				(type default)
			)
			(layer "F.Fab")
		)
		(fp_line
			(start -0.12065 -0.305054)
			(end -0.12065 -0.2794)
			(stroke
				(width 0.1)
				(type default)
			)
			(layer "F.Fab")
		)
		(fp_line
			(start -0.12065 -0.2794)
			(end 0.12065 -0.2794)
			(stroke
				(width 0.1)
				(type default)
			)
			(layer "F.Fab")
		)
		(fp_line
			(start -0.12065 0.2794)
			(end -0.12065 0.3048)
			(stroke
				(width 0.1)
				(type default)
			)
			(layer "F.Fab")
		)
		(fp_line
			(start -0.12065 0.3048)
			(end -0.67945 0.3048)
			(stroke
				(width 0.1)
				(type default)
			)
			(layer "F.Fab")
		)
		(fp_line
			(start 0.120396 0.2794)
			(end -0.12065 0.2794)
			(stroke
				(width 0.1)
				(type default)
			)
			(layer "F.Fab")
		)
		(fp_line
			(start 0.120396 0.3048)
			(end 0.120396 0.2794)
			(stroke
				(width 0.1)
				(type default)
			)
			(layer "F.Fab")
		)
		(fp_line
			(start 0.12065 -0.3048)
			(end 0.67945 -0.3048)
			(stroke
				(width 0.1)
				(type default)
			)
			(layer "F.Fab")
		)
		(fp_line
			(start 0.12065 -0.2794)
			(end 0.12065 -0.3048)
			(stroke
				(width 0.1)
				(type default)
			)
			(layer "F.Fab")
		)
		(fp_line
			(start 0.67945 -0.3048)
			(end 0.67945 0.3048)
			(stroke
				(width 0.1)
				(type default)
			)
			(layer "F.Fab")
		)
		(fp_line
			(start 0.67945 0.3048)
			(end 0.120396 0.3048)
			(stroke
				(width 0.1)
				(type default)
			)
			(layer "F.Fab")
		)
		(pad "1" smd circle
			(at -0.40005 0)
			(size 0 0)
			(layers "F.Cu" "F.Mask" "F.Paste")
			(net "P12V_E1S_SS_0")
		)
		(pad "2" smd circle
			(at 0.40005 0)
			(size 0 0)
			(layers "F.Cu" "F.Mask" "F.Paste")
			(net "GND")
		)
	)
)
